# SCM (Grand Teton) — schematic netlist excerpt (pin names and nets, part order shuffled) for the footprints in the layout excerpt that follows; sources: Cadence DE-HDL packaged netlist, KiCad conversion of 12092022_DA0F0TMDCD0_F0T_Management_Board_D_brd_V3_OCP.brd

U40  PCA9555PW  IC  pkg SMLF  page 28
  \int*\  = LED_POSTCODE_INT
  A1  = LED_POSTCODE_A1
  A2  = LED_POSTCODE_A2
  P00  = LED_POSTCODE_0_R1
  P01  = LED_POSTCODE_1_R1
  P02  = LED_POSTCODE_2_R1
  P03  = LED_POSTCODE_3_R1
  P04  = LED_POSTCODE_4_R1
  P05  = LED_POSTCODE_5_R1
  P06  = LED_POSTCODE_6_R1
  P07  = LED_POSTCODE_7_R1
  VSS  = GND
  P10  = FM_DEBUG_RST_BTN_N
  P11  = FM_DEBUG_PWR_BTN_N
  P12  = PWRGD_SYS_PWROK_R1
  P13  = RST_PLTRST_R2_N
  P14  = PWRGD_DSW_PWROK_R3
  P15  = FM_CPU_MSMI_CATERR_LVT3_R3_N
  P16  = FM_SLPS3_GF_R2_N
  P17  = FM_UART_SWITCH_N
  A0  = LED_POSTCODE_A0
  SCL  = SMB_DEBUG_AUX_LVC3_USB_R3_SCL
  SDA  = SMB_DEBUG_AUX_LVC3_USB_R3_SDA
  VDD  = P3V3_AUX

(kicad_pcb
	(version 20260206)
	(generator "pcbnew")
	(generator_version "10.0")
	(general
		(thickness 1.6)
		(legacy_teardrops no)
	)
	(paper "A4")
	(title_block
		(title "12092022_DA0F0TMDCD0_F0T_Management_Board_D_brd_V3_OCP.brd")
		(comment 1 "Grand Teton / footprints 1278-1278 of 1440")
	)
	(layers
		(0 "F.Cu" signal "TOP")
		(4 "In1.Cu" signal "GND")
		(6 "In2.Cu" signal "IN1")
		(8 "In3.Cu" signal "GND1")
		(10 "In4.Cu" signal "IN2")
		(12 "In5.Cu" signal "VCC")
		(14 "In6.Cu" signal "VCC1")
		(16 "In7.Cu" signal "IN3")
		(18 "In8.Cu" signal "GND2")
		(20 "In9.Cu" signal "IN4")
		(22 "In10.Cu" signal "GND3")
		(2 "B.Cu" signal "BOTTOM")
		(9 "F.Adhes" user "F.Adhesive")
		(11 "B.Adhes" user "B.Adhesive")
		(13 "F.Paste" user "Package Geometry/Pastemask Top")
		(15 "B.Paste" user "Package Geometry/Pastemask Bottom")
		(5 "F.SilkS" user "Ref Des/Silkscreen Top")
		(7 "B.SilkS" user "Ref Des/Silkscreen Bottom")
		(1 "F.Mask" user "Board Geometry/Soldermask Top")
		(3 "B.Mask" user "Board Geometry/Soldermask Bottom")
		(17 "Dwgs.User" user "User.Drawings")
		(19 "Cmts.User" user "User.Comments")
		(21 "Eco1.User" user "User.Eco1")
		(23 "Eco2.User" user "User.Eco2")
		(25 "Edge.Cuts" user "Board Geometry/Outline")
		(27 "Margin" user)
		(31 "F.CrtYd" user "Package Geometry/Place Bound Top")
		(29 "B.CrtYd" user "Package Geometry/Place Bound Bottom")
		(35 "F.Fab" user "Ref Des/Assembly Top")
		(33 "B.Fab" user "Ref Des/Assembly Bottom")
	)
	(footprint ""
		(layer "B.Cu")
		(at 57.63768 -89.72042)
		(property "Reference" "U40"
			(at 0.97282 4.66979 0)
			(unlocked yes)
			(layer "B.SilkS")
			(effects
				(font
					(size 0.7874 0.5842)
					(thickness 0.1524)
				)
				(justify left mirror)
			)
		)
		(property "Value" ""
			(at 0 0 0)
			(layer "B.Fab")
			(effects
				(font
					(size 1.27 1.27)
				)
				(justify mirror)
			)
		)
		(duplicate_pad_numbers_are_jumpers no)
		(fp_line
			(start -2.0066 -3.9624)
			(end -2.0066 3.9624)
			(stroke
				(width 0.1524)
				(type default)
			)
			(layer "B.SilkS")
		)
		(fp_line
			(start -2.0066 3.9624)
			(end 2.0066 3.9624)
			(stroke
				(width 0.1524)
				(type default)
			)
			(layer "B.SilkS")
		)
		(fp_line
			(start -0.5842 -3.9624)
			(end -2.0066 -3.9624)
			(stroke
				(width 0.1524)
				(type default)
			)
			(layer "B.SilkS")
		)
		(fp_line
			(start 0 -3.3782)
			(end -0.5842 -3.9624)
			(stroke
				(width 0.1524)
				(type default)
			)
			(layer "B.SilkS")
		)
		(fp_line
			(start 0.5842 -3.9624)
			(end 0 -3.3782)
			(stroke
				(width 0.1524)
				(type default)
			)
			(layer "B.SilkS")
		)
		(fp_line
			(start 2.0066 -3.9624)
			(end 0.5842 -3.9624)
			(stroke
				(width 0.1524)
				(type default)
			)
			(layer "B.SilkS")
		)
		(fp_line
			(start 2.0066 3.9624)
			(end 2.0066 -3.9624)
			(stroke
				(width 0.1524)
				(type default)
			)
			(layer "B.SilkS")
		)
		(fp_poly
			(pts
				(xy 3.502914 -3.90906) (xy 3.883914 -4.67106) (xy 3.121914 -4.67106)
			)
			(stroke
				(width 0)
				(type default)
			)
			(fill yes)
			(layer "B.SilkS")
		)
		(fp_line
			(start -3.7211 -3.80365)
			(end -2.2479 -3.80365)
			(stroke
				(width 0.1)
				(type default)
			)
			(layer "B.Fab")
		)
		(fp_line
			(start -3.7211 3.80365)
			(end -3.7211 -3.80365)
			(stroke
				(width 0.1)
				(type default)
			)
			(layer "B.Fab")
		)
		(fp_line
			(start -2.2479 -3.974846)
			(end 2.2479 -3.974846)
			(stroke
				(width 0.1)
				(type default)
			)
			(layer "B.Fab")
		)
		(fp_line
			(start -2.2479 -3.80365)
			(end -2.2479 -3.974846)
			(stroke
				(width 0.1)
				(type default)
			)
			(layer "B.Fab")
		)
		(fp_line
			(start -2.2479 3.80365)
			(end -3.7211 3.80365)
			(stroke
				(width 0.1)
				(type default)
			)
			(layer "B.Fab")
		)
		(fp_line
			(start -2.2479 3.9624)
			(end -2.2479 3.80365)
			(stroke
				(width 0.1)
				(type default)
			)
			(layer "B.Fab")
		)
		(fp_line
			(start 2.2479 -3.974846)
			(end 2.2479 -3.80365)
			(stroke
				(width 0.1)
				(type default)
			)
			(layer "B.Fab")
		)
		(fp_line
			(start 2.2479 -3.80365)
			(end 3.724402 -3.80365)
			(stroke
				(width 0.1)
				(type default)
			)
			(layer "B.Fab")
		)
		(fp_line
			(start 2.2479 3.80365)
			(end 2.2479 3.9624)
			(stroke
				(width 0.1)
				(type default)
			)
			(layer "B.Fab")
		)
		(fp_line
			(start 2.2479 3.9624)
			(end -2.2479 3.9624)
			(stroke
				(width 0.1)
				(type default)
			)
			(layer "B.Fab")
		)
		(fp_line
			(start 3.7211 -3.34645)
			(end 3.7211 -3.80365)
			(stroke
				(width 0.1)
				(type default)
			)
			(layer "B.Fab")
		)
		(fp_line
			(start 3.724402 -3.80365)
			(end 3.724402 3.80365)
			(stroke
				(width 0.1)
				(type default)
			)
			(layer "B.Fab")
		)
		(fp_line
			(start 3.724402 3.80365)
			(end 2.2479 3.80365)
			(stroke
				(width 0.1)
				(type default)
			)
			(layer "B.Fab")
		)
		(fp_poly
			(pts
				(xy 3.8862 -3.570986) (xy 4.6482 -3.189986) (xy 4.6482 -3.951986)
			)
			(stroke
				(width 0)
				(type default)
			)
			(fill yes)
			(layer "B.Fab")
		)
		(pad "1" smd rect
			(at 2.921 -3.57505 270)
			(size 0.3556 1.4986)
			(layers "B.Cu" "B.Mask" "B.Paste")
			(net "LED_POSTCODE_INT")
		)
		(pad "2" smd rect
			(at 2.921 -2.925064 270)
			(size 0.3556 1.4986)
			(layers "B.Cu" "B.Mask" "B.Paste")
			(net "LED_POSTCODE_A1")
		)
		(pad "3" smd rect
			(at 2.921 -2.275078 270)
			(size 0.3556 1.4986)
			(layers "B.Cu" "B.Mask" "B.Paste")
			(net "LED_POSTCODE_A2")
		)
		(pad "4" smd rect
			(at 2.921 -1.625092 270)
			(size 0.3556 1.4986)
			(layers "B.Cu" "B.Mask" "B.Paste")
			(net "LED_POSTCODE_0_R1")
		)
		(pad "5" smd rect
			(at 2.921 -0.975106 270)
			(size 0.3556 1.4986)
			(layers "B.Cu" "B.Mask" "B.Paste")
			(net "LED_POSTCODE_1_R1")
		)
		(pad "6" smd rect
			(at 2.921 -0.32512 270)
			(size 0.3556 1.4986)
			(layers "B.Cu" "B.Mask" "B.Paste")
			(net "LED_POSTCODE_2_R1")
		)
		(pad "7" smd rect
			(at 2.921 0.32512 270)
			(size 0.3556 1.4986)
			(layers "B.Cu" "B.Mask" "B.Paste")
			(net "LED_POSTCODE_3_R1")
		)
		(pad "8" smd rect
			(at 2.921 0.975106 270)
			(size 0.3556 1.4986)
			(layers "B.Cu" "B.Mask" "B.Paste")
			(net "LED_POSTCODE_4_R1")
		)
		(pad "9" smd rect
			(at 2.921 1.625092 270)
			(size 0.3556 1.4986)
			(layers "B.Cu" "B.Mask" "B.Paste")
			(net "LED_POSTCODE_5_R1")
		)
		(pad "10" smd rect
			(at 2.921 2.275078 270)
			(size 0.3556 1.4986)
			(layers "B.Cu" "B.Mask" "B.Paste")
			(net "LED_POSTCODE_6_R1")
		)
		(pad "11" smd rect
			(at 2.921 2.925064 270)
			(size 0.3556 1.4986)
			(layers "B.Cu" "B.Mask" "B.Paste")
			(net "LED_POSTCODE_7_R1")
		)
		(pad "12" smd rect
			(at 2.921 3.57505 270)
			(size 0.3556 1.4986)
			(layers "B.Cu" "B.Mask" "B.Paste")
			(net "GND")
		)
		(pad "13" smd rect
			(at -2.921 3.57505 270)
			(size 0.3556 1.4986)
			(layers "B.Cu" "B.Mask" "B.Paste")
			(net "FM_DEBUG_RST_BTN_N")
		)
		(pad "14" smd rect
			(at -2.921 2.925064 270)
			(size 0.3556 1.4986)
			(layers "B.Cu" "B.Mask" "B.Paste")
			(net "FM_DEBUG_PWR_BTN_N")
		)
		(pad "15" smd rect
			(at -2.921 2.275078 270)
			(size 0.3556 1.4986)
			(layers "B.Cu" "B.Mask" "B.Paste")
			(net "PWRGD_SYS_PWROK_R1")
		)
		(pad "16" smd rect
			(at -2.921 1.625092 270)
			(size 0.3556 1.4986)
			(layers "B.Cu" "B.Mask" "B.Paste")
			(net "RST_PLTRST_R2_N")
		)
		(pad "17" smd rect
			(at -2.921 0.975106 270)
			(size 0.3556 1.4986)
			(layers "B.Cu" "B.Mask" "B.Paste")
			(net "PWRGD_DSW_PWROK_R3")
		)
		(pad "18" smd rect
			(at -2.921 0.32512 270)
			(size 0.3556 1.4986)
			(layers "B.Cu" "B.Mask" "B.Paste")
			(net "FM_CPU_MSMI_CATERR_LVT3_R3_N")
		)
		(pad "19" smd rect
			(at -2.921 -0.32512 270)
			(size 0.3556 1.4986)
			(layers "B.Cu" "B.Mask" "B.Paste")
			(net "FM_SLPS3_GF_R2_N")
		)
		(pad "20" smd rect
			(at -2.921 -0.975106 270)
			(size 0.3556 1.4986)
			(layers "B.Cu" "B.Mask" "B.Paste")
			(net "FM_UART_SWITCH_N")
		)
		(pad "21" smd rect
			(at -2.921 -1.625092 270)
			(size 0.3556 1.4986)
			(layers "B.Cu" "B.Mask" "B.Paste")
			(net "LED_POSTCODE_A0")
		)
		(pad "22" smd rect
			(at -2.921 -2.275078 270)
			(size 0.3556 1.4986)
			(layers "B.Cu" "B.Mask" "B.Paste")
			(net "SMB_DEBUG_AUX_LVC3_USB_R3_SCL")
		)
		(pad "23" smd rect
			(at -2.921 -2.925064 270)
			(size 0.3556 1.4986)
			(layers "B.Cu" "B.Mask" "B.Paste")
			(net "SMB_DEBUG_AUX_LVC3_USB_R3_SDA")
		)
		(pad "24" smd rect
			(at -2.921 -3.57505 270)
			(size 0.3556 1.4986)
			(layers "B.Cu" "B.Mask" "B.Paste")
			(net "P3V3_AUX")
		)
	)
)
